FILE_TYPE = CONNECTIVITY;
{Allegro Design Entry HDL 17.2-2016 S081 (4005846) 1/11/2022}
"PAGE_NUMBER" = 140;
0"NC";
1"P3V3_AUX\g";
2"P3V3_AUX\g";
3"P3V3_AUX\g";
4"P3V3_AUX\g";
5"P3V3_AUX\g";
6"P3V3_AUX\g";
7"P3V3_AUX\g";
8"P3V3_AUX\g";
9"P3V3_AUX\g";
10"P3V3_AUX\g";
11"P3V3_AUX\g";
12"P3V3_AUX\g";
13"P3V3_AUX\g";
14"GND\g";
15"GND\g";
16"GND\g";
17"GND\g";
18"GND\g";
19"GND\g";
20"GND\g";
21"GND\g";
22"GND\g";
23"GND\g";
24"GND\g";
25"GND\g";
26"GND\g";
27"GND\g";
28"UART_BMC_BIC_R_RX";
29"UART_BMC_BIC_R_BUF_RX";
30"UART_BMC_BIC_BUF_RX";
31"FM_PDB_BUF_EN_R";
32"GPU_FPGA_RST_R_N";
33"GPU_FPGA_RST_R_BUF_N";
34"FM_UART_EN";
35"UART_BMC_BIC_RX";
36"GPU_FPGA_RST_R1_BUF_N";
37"RST_SWB_BIC_BUF_R_N";
38"BMC_MONITER_BUF_R";
39"RST_SWB_BIC_BUF_N";
40"BMC_MONITER_BUF";
41"RST_SWB_BIC_R_N";
42"FM_GPU_PWR_EN_R_BUF";
43"FM_GPU_PWR_EN_R1";
44"BMC_MONITER_R";
45"FM_GPU_PWR_EN_R";
%"Q_RES"
"2","(2525,2700)","0","pure_quanta","I121";
;
PART_NUMBER"CS24702JB10"
MATERIAL"CHIP"
VALUE"4.7K"
TOLERANCE"5%"
WATTAGE"1/16W"
PACK_TYPE"0402LF"
$LOCATION"R2926"
CDS_LIB"pure_quanta"
CDS_LOCATION"R2926"
$SEC"1"
CDS_SEC"1";
"A"
$PN"1"38;
"B"
$PN"2"16;
%"UNIVERSAL_GND"
"1","(2525,2475)","0","logical_power","I122";
;
HDL_POWER"GND"
CDS_LIB"logical_power";
"A"16;
%"UNIVERSAL_GND"
"1","(2625,1350)","0","logical_power","I125";
;
CDS_LIB"logical_power"
HDL_POWER"GND";
"A"17;
%"74LVC2G17GW"
"1","(1475,50)","0","pure_quanta","I127";
;
PART_NUMBER"AL2G0017005"
MATERIAL"IC"
VALUE"74LVC2G17GW"
PART_TYPE"SMLF"
$LOCATION"U196"
CDS_LMAN_SYM_OUTLINE"-225,275,225,-275"
NEEDS_NO_SIZE"TRUE"
CDS_LIB"pure_quanta"
CDS_LOCATION"U196"
$SEC"1"
CDS_SEC"1";
"B0"
$PN"6"43;
"A1"
$PN"3"32;
"A0"
$PN"1"45;
"GND"
$PN"2"23;
"B1"
$PN"4"36;
"VCC"
$PN"5"8;
%"UNIVERSAL_GND"
"1","(2625,100)","0","logical_power","I132";
;
CDS_LIB"logical_power"
HDL_POWER"GND";
"A"18;
%"UNIVERSAL_POWER"
"1","(1625,1300)","0","logical_power","I139";
;
HDL_POWER"P3V3_AUX"
CDS_LIB"logical_power";
"A"8;
%"Q_CAP"
"1","(1625,975)","0","pure_quanta","I140";
;
PART_NUMBER"CH4104K1B00"
PACK_TYPE"0402"
VOLTAGE"25V"
MATERIAL"X7R"
VALUE"0.1UF"
TOLERANCE"10%"
$LOCATION"C1770"
CDS_LIB"pure_quanta"
CDS_LOCATION"C1770"
$SEC"1"
CDS_SEC"1";
"B"
$PN"2"21;
"A"
$PN"1"8;
%"UNIVERSAL_GND"
"1","(1625,750)","0","logical_power","I141";
;
CDS_LIB"logical_power"
HDL_POWER"GND";
"A"21;
%"UNIVERSAL_GND"
"1","(1500,-550)","0","logical_power","I142";
;
CDS_LIB"logical_power"
HDL_POWER"GND";
"A"23;
%"Q_RES"
"2","(2575,850)","0","pure_quanta","I147";
;
PART_NUMBER"CS24702JB10"
TOLERANCE"5%"
VALUE"4.7K"
WATTAGE"1/16W"
MATERIAL"EMPTY"
PACK_TYPE"0402LF"
$LOCATION"R2912"
CDS_LIB"pure_quanta"
CDS_LOCATION"R2912"
$SEC"1"
CDS_SEC"1";
"A"
$PN"1"9;
"B"
$PN"2"43;
%"UNIVERSAL_POWER"
"1","(2575,1100)","0","logical_power","I148";
;
HDL_POWER"P3V3_AUX"
CDS_LIB"logical_power";
"A"9;
%"Q_RES"
"2","(2600,2050)","0","pure_quanta","I153";
;
PART_NUMBER"CS24702JB10"
MATERIAL"EMPTY"
PACK_TYPE"0402LF"
VALUE"4.7K"
WATTAGE"1/16W"
TOLERANCE"5%"
$LOCATION"R2911"
CDS_LIB"pure_quanta"
CDS_LOCATION"R2911"
$SEC"1"
CDS_SEC"1";
"A"
$PN"1"6;
"B"
$PN"2"37;
%"UNIVERSAL_GND"
"1","(-50,225)","0","logical_power","I159";
;
CDS_LIB"logical_power"
HDL_POWER"GND";
"A"27;
%"Q_RES"
"2","(-50,400)","0","pure_quanta","I160";
;
PART_NUMBER"CS24702JB10"
TOLERANCE"5%"
MATERIAL"CHIP"
PACK_TYPE"0402LF"
VALUE"4.7K"
WATTAGE"1/16W"
$LOCATION"R2937"
CDS_LIB"pure_quanta"
CDS_LOCATION"R2937"
$SEC"1"
CDS_SEC"1";
"A"
$PN"1"45;
"B"
$PN"2"27;
%"UNIVERSAL_POWER"
"1","(-75,1125)","0","logical_power","I161";
;
HDL_POWER"P3V3_AUX"
CDS_LIB"logical_power";
"A"12;
%"Q_RES"
"2","(-75,875)","0","pure_quanta","I162";
;
PART_NUMBER"CS41002FB09"
PACK_TYPE"0402LF"
TOLERANCE"1%"
VALUE"100K"
MATERIAL"EMPTY"
WATTAGE"1/16W"
$LOCATION"R2936"
CDS_LIB"pure_quanta"
CDS_LOCATION"R2936"
$SEC"1"
CDS_SEC"1";
"A"
$PN"1"12;
"B"
$PN"2"45;
%"UNIVERSAL_POWER"
"1","(-325,-1050)","0","logical_power","I165";
;
HDL_POWER"P3V3_AUX"
CDS_LIB"logical_power";
"A"2;
%"Q_CAP"
"1","(-325,-1375)","0","pure_quanta","I166";
;
PART_NUMBER"CH4104K1B00"
VALUE"0.1UF"
VOLTAGE"25V"
PACK_TYPE"0402"
MATERIAL"X7R"
TOLERANCE"10%"
$LOCATION"C1803"
CDS_LIB"pure_quanta"
CDS_LOCATION"C1803"
$SEC"1"
CDS_SEC"1";
"B"
$PN"2"15;
"A"
$PN"1"2;
%"UNIVERSAL_GND"
"1","(-325,-1600)","0","logical_power","I167";
;
CDS_LIB"logical_power"
HDL_POWER"GND";
"A"15;
%"Q_RES"
"1","(-1575,-1850)","0","pure_quanta","I170";
;
PART_NUMBER"CS00002JB13"
PACK_TYPE"0402LF"
MATERIAL"CHIP"
VALUE"0"
$LOCATION"R3033"
WATTAGE"1/16W"
TOLERANCE"5%"
CDS_LIB"pure_quanta"
CDS_LOCATION"R3033"
$SEC"1"
CDS_SEC"1";
"B"
$PN"2"28;
"A"
$PN"1"35;
%"UNIVERSAL_POWER"
"1","(0,0)","0","logical_power","I174";
;
HDL_POWER"P3V3_AUX"
CDS_LIB"logical_power";
"A"3;
%"UNIVERSAL_GND"
"1","(2650,-1025)","0","logical_power","I178";
;
CDS_LIB"logical_power"
HDL_POWER"GND";
"A"22;
%"UNIVERSAL_POWER"
"1","(2650,-75)","0","logical_power","I183";
;
HDL_POWER"P3V3_AUX"
CDS_LIB"logical_power";
"A"7;
%"UNIVERSAL_GND"
"1","(25,-900)","0","logical_power","I184";
;
HDL_POWER"GND"
CDS_LIB"logical_power";
"A"24;
%"Q_RES"
"2","(2650,-325)","0","pure_quanta","I190";
;
PART_NUMBER"CS24702JB10"
TOLERANCE"5%"
MATERIAL"EMPTY"
WATTAGE"1/16W"
VALUE"4.7K"
PACK_TYPE"0402LF"
$LOCATION"R3317"
CDS_LIB"pure_quanta"
CDS_LOCATION"R3317"
$SEC"1"
CDS_SEC"1";
"A"
$PN"1"7;
"B"
$PN"2"36;
%"Q_RES"
"2","(2650,-800)","0","pure_quanta","I191";
;
PART_NUMBER"CS31002FB08"
WATTAGE"1/16W"
MATERIAL"CHIP"
TOLERANCE"1%"
PACK_TYPE"0402LF"
VALUE"10K"
$LOCATION"R3509"
CDS_LIB"pure_quanta"
CDS_LOCATION"R3509"
$SEC"1"
CDS_SEC"1";
"A"
$PN"1"36;
"B"
$PN"2"22;
%"Q_RES"
"2","(25,-725)","0","pure_quanta","I192";
;
PART_NUMBER"CS31002FB08"
VALUE"10K"
WATTAGE"1/16W"
TOLERANCE"1%"
MATERIAL"CHIP"
PACK_TYPE"0402LF"
$LOCATION"R3507"
CDS_LIB"pure_quanta"
CDS_LOCATION"R3507"
$SEC"1"
CDS_SEC"1";
"A"
$PN"1"32;
"B"
$PN"2"24;
%"Q_RES"
"2","(0,-250)","0","pure_quanta","I193";
;
PART_NUMBER"CS24702JB10"
VALUE"4.7K"
TOLERANCE"5%"
WATTAGE"1/16W"
MATERIAL"EMPTY"
PACK_TYPE"0402LF"
$LOCATION"R3506"
CDS_LIB"pure_quanta"
CDS_LOCATION"R3506"
$SEC"1"
CDS_SEC"1";
"A"
$PN"1"3;
"B"
$PN"2"32;
%"Q_RES"
"2","(2625,325)","0","pure_quanta","I194";
;
PART_NUMBER"CS35492FB03"
PACK_TYPE"0402LF"
TOLERANCE"1%"
VALUE"54.9K"
WATTAGE"1/16W"
MATERIAL"CHIP"
$LOCATION"R3508"
CDS_LIB"pure_quanta"
CDS_LOCATION"R3508"
$SEC"1"
CDS_SEC"1";
"A"
$PN"1"43;
"B"
$PN"2"18;
%"74LVC1G126SE7"
"1","(-550,-1900)","0","pure_quanta","I195";
;
PART_NUMBER"AL1G0126009"
PART_TYPE"SMLF"
MATERIAL"IC"
VALUE"74LVC1G126SE-7"
LOCATION"U204"
CDS_LIB"pure_quanta"
CDS_LMAN_SYM_OUTLINE"-100,100,100,-100"
NEEDS_NO_SIZE"TRUE"
$SEC"1"
CDS_SEC"1";
"OE"
$PN"1"34;
"GND"
$PN"3"14;
"VCC"
$PN"5"2;
"Y"
$PN"4"29;
"A"
$PN"2"28;
%"UNIVERSAL_GND"
"1","(-550,-2300)","0","logical_power","I196";
;
CDS_LIB"logical_power"
HDL_POWER"GND";
"A"14;
%"Q_RES"
"1","(650,-1900)","0","pure_quanta","I197";
;
PART_NUMBER"CS03322FB03"
PACK_TYPE"0402LF"
MATERIAL"CHIP"
VALUE"33.2"
LOCATION"R3036"
CDS_LIB"pure_quanta"
WATTAGE"1/16W"
TOLERANCE"1%"
$SEC"1"
CDS_SEC"1";
"B"
$PN"2"30;
"A"
$PN"1"29;
%"Q_RES"
"2","(0,2150)","0","pure_quanta","I198";
;
PART_NUMBER"CS24702JB10"
VALUE"4.7K"
TOLERANCE"5%"
WATTAGE"1/16W"
MATERIAL"CHIP"
PACK_TYPE"0402LF"
LOCATION"R2909"
CDS_LIB"pure_quanta"
$SEC"1"
CDS_SEC"1";
"A"
$PN"1"5;
"B"
$PN"2"41;
%"UNIVERSAL_POWER"
"1","(-1900,-1200)","0","logical_power","I199";
;
HDL_POWER"P3V3_AUX"
CDS_LIB"logical_power";
"A"4;
%"Q_RES"
"2","(-1900,-1525)","0","pure_quanta","I200";
;
PART_NUMBER"CS41002FB09"
MATERIAL"CHIP"
PACK_TYPE"0402LF"
TOLERANCE"1%"
WATTAGE"1/16W"
VALUE"100K"
LOCATION"R4515"
CDS_LIB"pure_quanta"
$SEC"1"
CDS_SEC"1";
"A"
$PN"1"4;
"B"
$PN"2"35;
%"UNIVERSAL_POWER"
"1","(400,-1250)","0","logical_power","I201";
;
HDL_POWER"P3V3_AUX"
CDS_LIB"logical_power";
"A"1;
%"Q_RES"
"2","(400,-1575)","0","pure_quanta","I202";
;
PART_NUMBER"CS41002FB09"
PACK_TYPE"0402LF"
TOLERANCE"1%"
VALUE"100K"
MATERIAL"EMPTY"
WATTAGE"1/16W"
LOCATION"R4173"
CDS_LIB"pure_quanta"
$SEC"1"
CDS_SEC"1";
"A"
$PN"1"1;
"B"
$PN"2"29;
%"Q_RES"
"2","(2625,1575)","0","pure_quanta","I203";
;
PART_NUMBER"CS41002FB09"
TOLERANCE"1%"
VALUE"100K"
PACK_TYPE"0402LF"
WATTAGE"1/16W"
MATERIAL"CHIP"
LOCATION"R2927"
CDS_LIB"pure_quanta"
$SEC"1"
CDS_SEC"1";
"A"
$PN"1"37;
"B"
$PN"2"17;
%"Q_RES"
"1","(2825,600)","0","pure_quanta","I204";
;
PART_NUMBER"CS04992FB07"
VALUE"49.9"
MATERIAL"CHIP"
LOCATION"R2925"
PACK_TYPE"0402LF"
TOLERANCE"1%"
WATTAGE"1/16W"
CDS_LIB"pure_quanta"
$SEC"1"
CDS_SEC"1";
"B"
$PN"2"42;
"A"
$PN"1"43;
%"Q_RES"
"1","(2900,-525)","0","pure_quanta","I205";
;
PART_NUMBER"CS04992FB07"
VALUE"49.9"
MATERIAL"CHIP"
LOCATION"R3315"
PACK_TYPE"0402LF"
TOLERANCE"1%"
WATTAGE"1/16W"
CDS_LIB"pure_quanta"
$SEC"1"
CDS_SEC"1";
"B"
$PN"2"33;
"A"
$PN"1"36;
%"Q_RES"
"1","(2850,3000)","0","pure_quanta","I206";
;
PART_NUMBER"CS04992FB07"
VALUE"49.9"
MATERIAL"CHIP"
LOCATION"R2917"
PACK_TYPE"0402LF"
TOLERANCE"1%"
WATTAGE"1/16W"
CDS_LIB"pure_quanta"
$SEC"1"
CDS_SEC"1";
"B"
$PN"2"40;
"A"
$PN"1"38;
%"Q_RES"
"1","(2925,1875)","0","pure_quanta","I207";
;
PART_NUMBER"CS04992FB07"
MATERIAL"CHIP"
VALUE"49.9"
LOCATION"R2924"
CDS_LIB"pure_quanta"
WATTAGE"1/16W"
TOLERANCE"1%"
PACK_TYPE"0402LF"
$SEC"1"
CDS_SEC"1";
"B"
$PN"2"39;
"A"
$PN"1"37;
%"Q_RES"
"1","(-1575,-1950)","0","pure_quanta","I208";
;
PART_NUMBER"CS03322FB03"
TOLERANCE"1%"
VALUE"33.2"
PACK_TYPE"0402LF"
MATERIAL"CHIP"
LOCATION"R3063"
CDS_LIB"pure_quanta"
WATTAGE"1/16W"
$SEC"1"
CDS_SEC"1";
"B"
$PN"2"34;
"A"
$PN"1"31;
%"74LVC2G17GW"
"1","(1475,2450)","0","pure_quanta","I65";
;
PART_NUMBER"AL2G0017005"
PART_TYPE"SMLF"
MATERIAL"IC"
VALUE"74LVC2G17GW"
$LOCATION"U195"
CDS_LMAN_SYM_OUTLINE"-225,275,225,-275"
NEEDS_NO_SIZE"TRUE"
CDS_LIB"pure_quanta"
CDS_LOCATION"U195"
$SEC"1"
CDS_SEC"1";
"B0"
$PN"6"38;
"A1"
$PN"3"41;
"A0"
$PN"1"44;
"GND"
$PN"2"20;
"B1"
$PN"4"37;
"VCC"
$PN"5"13;
%"UNIVERSAL_POWER"
"1","(0,3525)","0","logical_power","I67";
;
HDL_POWER"P3V3_AUX"
CDS_LIB"logical_power";
"A"11;
%"Q_RES"
"2","(0,3275)","0","pure_quanta","I68";
;
PART_NUMBER"CS41002FB09"
TOLERANCE"1%"
WATTAGE"1/16W"
MATERIAL"EMPTY"
PACK_TYPE"0402LF"
VALUE"100K"
$LOCATION"R2815"
CDS_LIB"pure_quanta"
CDS_LOCATION"R2815"
$SEC"1"
CDS_SEC"1";
"A"
$PN"1"11;
"B"
$PN"2"44;
%"UNIVERSAL_GND"
"1","(25,2600)","0","logical_power","I69";
;
CDS_LIB"logical_power"
HDL_POWER"GND";
"A"25;
%"UNIVERSAL_POWER"
"1","(0,2400)","0","logical_power","I71";
;
HDL_POWER"P3V3_AUX"
CDS_LIB"logical_power";
"A"5;
%"UNIVERSAL_GND"
"1","(25,1500)","0","logical_power","I74";
;
HDL_POWER"GND"
CDS_LIB"logical_power";
"A"26;
%"UNIVERSAL_GND"
"1","(1500,1850)","0","logical_power","I76";
;
CDS_LIB"logical_power"
HDL_POWER"GND";
"A"20;
%"Q_RES"
"2","(2500,3225)","0","pure_quanta","I78";
;
PART_NUMBER"CS24702JB10"
PACK_TYPE"0402LF"
TOLERANCE"5%"
WATTAGE"1/16W"
MATERIAL"EMPTY"
VALUE"4.7K"
$LOCATION"R2820"
CDS_LIB"pure_quanta"
CDS_LOCATION"R2820"
$SEC"1"
CDS_SEC"1";
"A"
$PN"1"10;
"B"
$PN"2"38;
%"UNIVERSAL_POWER"
"1","(2500,3475)","0","logical_power","I80";
;
HDL_POWER"P3V3_AUX"
CDS_LIB"logical_power";
"A"10;
%"UNIVERSAL_POWER"
"1","(2600,2300)","0","logical_power","I83";
;
HDL_POWER"P3V3_AUX"
CDS_LIB"logical_power";
"A"6;
%"UNIVERSAL_POWER"
"1","(1625,3700)","0","logical_power","I87";
;
HDL_POWER"P3V3_AUX"
CDS_LIB"logical_power";
"A"13;
%"UNIVERSAL_GND"
"1","(1625,3150)","0","logical_power","I88";
;
CDS_LIB"logical_power"
HDL_POWER"GND";
"A"19;
%"Q_CAP"
"1","(1625,3375)","0","pure_quanta","I89";
;
PART_NUMBER"CH4104K1B00"
VALUE"0.1UF"
VOLTAGE"25V"
TOLERANCE"10%"
MATERIAL"X7R"
PACK_TYPE"0402"
$LOCATION"C1769"
CDS_LIB"pure_quanta"
CDS_LOCATION"C1769"
$SEC"1"
CDS_SEC"1";
"B"
$PN"2"19;
"A"
$PN"1"13;
%"Q_RES"
"2","(25,2800)","0","pure_quanta","I92";
;
PART_NUMBER"CS24702JB10"
PACK_TYPE"0402LF"
VALUE"4.7K"
TOLERANCE"5%"
WATTAGE"1/16W"
MATERIAL"CHIP"
$LOCATION"R2915"
CDS_LIB"pure_quanta"
CDS_LOCATION"R2915"
$SEC"1"
CDS_SEC"1";
"A"
$PN"1"44;
"B"
$PN"2"25;
%"Q_RES"
"2","(25,1675)","0","pure_quanta","I93";
;
PART_NUMBER"CS24702JB10"
TOLERANCE"5%"
PACK_TYPE"0402LF"
MATERIAL"EMPTY"
WATTAGE"1/16W"
VALUE"4.7K"
$LOCATION"R2916"
CDS_LIB"pure_quanta"
CDS_LOCATION"R2916"
$SEC"1"
CDS_SEC"1";
"A"
$PN"1"41;
"B"
$PN"2"26;
END.
